(kicad_pcb
	(version 20260206)
	(generator "pcbnew")
	(generator_version "10.0")
	(general
		(thickness 1.6)
		(legacy_teardrops no)
	)
	(paper "A4")
	(title_block
		(title "Bryce Canyon_IOM_M2_16342-2_OCP.brd")
		(comment 1 "Bryce Canyon / footprints 829-836 of 1146")
	)
	(layers
		(0 "F.Cu" signal "TOP")
		(4 "In1.Cu" signal "L2GND")
		(6 "In2.Cu" signal "L3")
		(8 "In3.Cu" signal "L4VCC")
		(10 "In4.Cu" signal "L5VCC")
		(12 "In5.Cu" signal "L6")
		(14 "In6.Cu" signal "L7GND")
		(2 "B.Cu" signal "BOTTOM")
		(9 "F.Adhes" user "F.Adhesive")
		(11 "B.Adhes" user "B.Adhesive")
		(13 "F.Paste" user "Package Geometry/Pastemask Top")
		(15 "B.Paste" user "Package Geometry/Pastemask Bottom")
		(5 "F.SilkS" user "Ref Des/Silkscreen Top")
		(7 "B.SilkS" user "Ref Des/Silkscreen Bottom")
		(1 "F.Mask" user "Board Geometry/Soldermask Top")
		(3 "B.Mask" user "Board Geometry/Soldermask Bottom")
		(17 "Dwgs.User" user "User.Drawings")
		(19 "Cmts.User" user "User.Comments")
		(21 "Eco1.User" user "User.Eco1")
		(23 "Eco2.User" user "User.Eco2")
		(25 "Edge.Cuts" user "Board Geometry/Outline")
		(27 "Margin" user)
		(31 "F.CrtYd" user "Package Geometry/Place Bound Top")
		(29 "B.CrtYd" user "Package Geometry/Place Bound Bottom")
		(35 "F.Fab" user "Ref Des/Assembly Top")
		(33 "B.Fab" user "Ref Des/Assembly Bottom")
	)
	(footprint ""
		(layer "B.Cu")
		(at 42.351198 -127.978916)
		(property "Reference" "R325"
			(at 0 0 0)
			(layer "B.SilkS")
			(hide yes)
			(effects
				(font
					(size 1.27 1.27)
				)
				(justify mirror)
			)
		)
		(property "Value" "0R2J-2-GP"
			(at -0.064008 -3.993896 0)
			(unlocked yes)
			(layer "B.Fab")
			(hide yes)
			(effects
				(font
					(size 1.016 1.016)
					(thickness 0.1524)
				)
				(justify mirror)
			)
		)
		(property "Device Type" "R402H16"
			(at -0.064008 -5.517896 0)
			(unlocked yes)
			(layer "B.Fab")
			(hide yes)
			(effects
				(font
					(size 1.016 1.016)
					(thickness 0.1524)
				)
				(justify mirror)
			)
		)
		(duplicate_pad_numbers_are_jumpers no)
		(fp_line
			(start -0.508 -0.9398)
			(end 0.508 -0.9398)
			(stroke
				(width 0.1524)
				(type default)
			)
			(layer "B.SilkS")
		)
		(fp_line
			(start 0.508 -0.9398)
			(end 0.508 0.9398)
			(stroke
				(width 0.1524)
				(type default)
			)
			(layer "B.SilkS")
		)
		(fp_rect
			(start 0.508 0.9398)
			(end -0.508 -0.9398)
			(stroke
				(width 0)
				(type default)
			)
			(fill no)
			(layer "B.CrtYd")
		)
		(fp_rect
			(start 0.508 0.9398)
			(end -0.508 -0.9398)
			(stroke
				(width 0)
				(type default)
			)
			(fill no)
			(layer "B.Fab")
		)
		(pad "1" smd custom
			(at 0 -0.4445 180)
			(size 0.1397 0.1397)
			(layers "B.Cu" "B.Mask" "B.Paste")
			(net "BMC0_SRST_N")
			(options
				(clearance outline)
				(anchor circle)
			)
			(primitives
				(gr_poly
					(pts
						(arc
							(start -0.1778 0.2794)
							(mid -0.249642 0.249642)
							(end -0.2794 0.1778)
						)
						(arc
							(start -0.2794 -0.1778)
							(mid -0.249642 -0.249642)
							(end -0.1778 -0.2794)
						)
						(arc
							(start 0.1778 -0.2794)
							(mid 0.249642 -0.249642)
							(end 0.2794 -0.1778)
						)
						(arc
							(start 0.2794 0.1778)
							(mid 0.249642 0.249642)
							(end 0.1778 0.2794)
						)
					)
					(width 0)
					(fill yes)
				)
			)
		)
		(pad "2" smd custom
			(at 0 0.4445 180)
			(size 0.1397 0.1397)
			(layers "B.Cu" "B.Mask" "B.Paste")
			(net "FM_BMC_RESET_N")
			(options
				(clearance outline)
				(anchor circle)
			)
			(primitives
				(gr_poly
					(pts
						(arc
							(start -0.1778 0.2794)
							(mid -0.249642 0.249642)
							(end -0.2794 0.1778)
						)
						(arc
							(start -0.2794 -0.1778)
							(mid -0.249642 -0.249642)
							(end -0.1778 -0.2794)
						)
						(arc
							(start 0.1778 -0.2794)
							(mid 0.249642 -0.249642)
							(end 0.2794 -0.1778)
						)
						(arc
							(start 0.2794 0.1778)
							(mid 0.249642 0.249642)
							(end 0.1778 0.2794)
						)
					)
					(width 0)
					(fill yes)
				)
			)
		)
	)
	(footprint ""
		(layer "B.Cu")
		(at 11.345672 -144.098264 -90)
		(property "Reference" "C65"
			(at 0 0 90)
			(layer "B.SilkS")
			(hide yes)
			(effects
				(font
					(size 1.27 1.27)
				)
				(justify mirror)
			)
		)
		(property "Value" "SC1U16V3KX-5GP"
			(at 0 -2.8194 270)
			(unlocked yes)
			(layer "B.Fab")
			(hide yes)
			(effects
				(font
					(size 1.016 1.016)
					(thickness 0.1524)
				)
				(justify mirror)
			)
		)
		(property "Device Type" "C603H36"
			(at 0 -4.3434 270)
			(unlocked yes)
			(layer "B.Fab")
			(hide yes)
			(effects
				(font
					(size 1.016 1.016)
					(thickness 0.1524)
				)
				(justify mirror)
			)
		)
		(duplicate_pad_numbers_are_jumpers no)
		(fp_line
			(start -0.508 0)
			(end 0.508 0)
			(stroke
				(width 0.2032)
				(type default)
			)
			(layer "B.SilkS")
		)
		(fp_rect
			(start 0.5842 1.3335)
			(end -0.5842 -1.3335)
			(stroke
				(width 0)
				(type default)
			)
			(fill no)
			(layer "B.CrtYd")
		)
		(fp_rect
			(start 0.5842 1.3335)
			(end -0.5842 -1.3335)
			(stroke
				(width 0)
				(type default)
			)
			(fill no)
			(layer "B.Fab")
		)
		(pad "1" smd custom
			(at 0 -0.762 90)
			(size 0.2159 0.2159)
			(layers "B.Cu" "B.Mask" "B.Paste")
			(net "P2V5_STBY")
			(options
				(clearance outline)
				(anchor circle)
			)
			(primitives
				(gr_poly
					(pts
						(arc
							(start -0.3302 0.4318)
							(mid -0.402042 0.402042)
							(end -0.4318 0.3302)
						)
						(arc
							(start -0.4318 -0.3302)
							(mid -0.402042 -0.402042)
							(end -0.3302 -0.4318)
						)
						(arc
							(start 0.3302 -0.4318)
							(mid 0.402042 -0.402042)
							(end 0.4318 -0.3302)
						)
						(arc
							(start 0.4318 0.3302)
							(mid 0.402042 0.402042)
							(end 0.3302 0.4318)
						)
					)
					(width 0)
					(fill yes)
				)
			)
		)
		(pad "2" smd custom
			(at 0 0.762 90)
			(size 0.2159 0.2159)
			(layers "B.Cu" "B.Mask" "B.Paste")
			(net "GND")
			(options
				(clearance outline)
				(anchor circle)
			)
			(primitives
				(gr_poly
					(pts
						(arc
							(start -0.3302 0.4318)
							(mid -0.402042 0.402042)
							(end -0.4318 0.3302)
						)
						(arc
							(start -0.4318 -0.3302)
							(mid -0.402042 -0.402042)
							(end -0.3302 -0.4318)
						)
						(arc
							(start 0.3302 -0.4318)
							(mid 0.402042 -0.402042)
							(end 0.4318 -0.3302)
						)
						(arc
							(start 0.4318 0.3302)
							(mid 0.402042 0.402042)
							(end 0.3302 0.4318)
						)
					)
					(width 0)
					(fill yes)
				)
			)
		)
	)
	(footprint ""
		(layer "B.Cu")
		(at 32.5374 -162.306 90)
		(property "Reference" "R703"
			(at 0 0 90)
			(layer "B.SilkS")
			(hide yes)
			(effects
				(font
					(size 1.27 1.27)
				)
				(justify mirror)
			)
		)
		(property "Value" "4K7R2F-GP"
			(at -0.064008 -3.993896 90)
			(unlocked yes)
			(layer "B.Fab")
			(hide yes)
			(effects
				(font
					(size 1.016 1.016)
					(thickness 0.1524)
				)
				(justify mirror)
			)
		)
		(property "Device Type" "R402H16"
			(at -0.064008 -5.517896 90)
			(unlocked yes)
			(layer "B.Fab")
			(hide yes)
			(effects
				(font
					(size 1.016 1.016)
					(thickness 0.1524)
				)
				(justify mirror)
			)
		)
		(duplicate_pad_numbers_are_jumpers no)
		(fp_line
			(start 0.508 -0.9398)
			(end 0.508 0.9398)
			(stroke
				(width 0.1524)
				(type default)
			)
			(layer "B.SilkS")
		)
		(fp_line
			(start -0.508 -0.9398)
			(end 0.508 -0.9398)
			(stroke
				(width 0.1524)
				(type default)
			)
			(layer "B.SilkS")
		)
		(fp_rect
			(start 0.508 0.9398)
			(end -0.508 -0.9398)
			(stroke
				(width 0)
				(type default)
			)
			(fill no)
			(layer "B.CrtYd")
		)
		(fp_rect
			(start 0.508 0.9398)
			(end -0.508 -0.9398)
			(stroke
				(width 0)
				(type default)
			)
			(fill no)
			(layer "B.Fab")
		)
		(pad "1" smd custom
			(at 0 -0.4445 270)
			(size 0.1397 0.1397)
			(layers "B.Cu" "B.Mask" "B.Paste")
			(net "GND")
			(options
				(clearance outline)
				(anchor circle)
			)
			(primitives
				(gr_poly
					(pts
						(arc
							(start -0.1778 0.2794)
							(mid -0.249642 0.249642)
							(end -0.2794 0.1778)
						)
						(arc
							(start -0.2794 -0.1778)
							(mid -0.249642 -0.249642)
							(end -0.1778 -0.2794)
						)
						(arc
							(start 0.1778 -0.2794)
							(mid 0.249642 -0.249642)
							(end 0.2794 -0.1778)
						)
						(arc
							(start 0.2794 0.1778)
							(mid 0.249642 0.249642)
							(end 0.1778 0.2794)
						)
					)
					(width 0)
					(fill yes)
				)
			)
		)
		(pad "2" smd custom
			(at 0 0.4445 270)
			(size 0.1397 0.1397)
			(layers "B.Cu" "B.Mask" "B.Paste")
			(net "IOM_TYPE1")
			(options
				(clearance outline)
				(anchor circle)
			)
			(primitives
				(gr_poly
					(pts
						(arc
							(start -0.1778 0.2794)
							(mid -0.249642 0.249642)
							(end -0.2794 0.1778)
						)
						(arc
							(start -0.2794 -0.1778)
							(mid -0.249642 -0.249642)
							(end -0.1778 -0.2794)
						)
						(arc
							(start 0.1778 -0.2794)
							(mid 0.249642 -0.249642)
							(end 0.2794 -0.1778)
						)
						(arc
							(start 0.2794 0.1778)
							(mid 0.249642 0.249642)
							(end 0.1778 0.2794)
						)
					)
					(width 0)
					(fill yes)
				)
			)
		)
	)
	(footprint ""
		(layer "B.Cu")
		(at 60.8838 -141.2494 -90)
		(property "Reference" "R176"
			(at 0 0 90)
			(layer "B.SilkS")
			(hide yes)
			(effects
				(font
					(size 1.27 1.27)
				)
				(justify mirror)
			)
		)
		(property "Value" "0R2J-2-GP"
			(at -0.064008 -3.993896 270)
			(unlocked yes)
			(layer "B.Fab")
			(hide yes)
			(effects
				(font
					(size 1.016 1.016)
					(thickness 0.1524)
				)
				(justify mirror)
			)
		)
		(property "Device Type" "R402H16"
			(at -0.064008 -5.517896 270)
			(unlocked yes)
			(layer "B.Fab")
			(hide yes)
			(effects
				(font
					(size 1.016 1.016)
					(thickness 0.1524)
				)
				(justify mirror)
			)
		)
		(duplicate_pad_numbers_are_jumpers no)
		(fp_line
			(start -0.508 -0.9398)
			(end 0.508 -0.9398)
			(stroke
				(width 0.1524)
				(type default)
			)
			(layer "B.SilkS")
		)
		(fp_line
			(start 0.508 -0.9398)
			(end 0.508 0.9398)
			(stroke
				(width 0.1524)
				(type default)
			)
			(layer "B.SilkS")
		)
		(fp_rect
			(start 0.508 0.9398)
			(end -0.508 -0.9398)
			(stroke
				(width 0)
				(type default)
			)
			(fill no)
			(layer "B.CrtYd")
		)
		(fp_rect
			(start 0.508 0.9398)
			(end -0.508 -0.9398)
			(stroke
				(width 0)
				(type default)
			)
			(fill no)
			(layer "B.Fab")
		)
		(pad "1" smd custom
			(at 0 -0.4445 90)
			(size 0.1397 0.1397)
			(layers "B.Cu" "B.Mask" "B.Paste")
			(net "I2C_M2_2_SDA")
			(options
				(clearance outline)
				(anchor circle)
			)
			(primitives
				(gr_poly
					(pts
						(arc
							(start -0.1778 0.2794)
							(mid -0.249642 0.249642)
							(end -0.2794 0.1778)
						)
						(arc
							(start -0.2794 -0.1778)
							(mid -0.249642 -0.249642)
							(end -0.1778 -0.2794)
						)
						(arc
							(start 0.1778 -0.2794)
							(mid 0.249642 -0.249642)
							(end 0.2794 -0.1778)
						)
						(arc
							(start 0.2794 0.1778)
							(mid 0.249642 0.249642)
							(end 0.1778 0.2794)
						)
					)
					(width 0)
					(fill yes)
				)
			)
		)
		(pad "2" smd custom
			(at 0 0.4445 90)
			(size 0.1397 0.1397)
			(layers "B.Cu" "B.Mask" "B.Paste")
			(net "BMC_SMB9_DAT")
			(options
				(clearance outline)
				(anchor circle)
			)
			(primitives
				(gr_poly
					(pts
						(arc
							(start -0.1778 0.2794)
							(mid -0.249642 0.249642)
							(end -0.2794 0.1778)
						)
						(arc
							(start -0.2794 -0.1778)
							(mid -0.249642 -0.249642)
							(end -0.1778 -0.2794)
						)
						(arc
							(start 0.1778 -0.2794)
							(mid 0.249642 -0.249642)
							(end 0.2794 -0.1778)
						)
						(arc
							(start 0.2794 0.1778)
							(mid 0.249642 0.249642)
							(end 0.1778 0.2794)
						)
					)
					(width 0)
					(fill yes)
				)
			)
		)
	)
	(footprint ""
		(layer "B.Cu")
		(at 55.372 -119.6594 90)
		(property "Reference" "R337"
			(at 0 0 90)
			(layer "B.SilkS")
			(hide yes)
			(effects
				(font
					(size 1.27 1.27)
				)
				(justify mirror)
			)
		)
		(property "Value" "4K7R2F-GP"
			(at -0.064008 -3.993896 90)
			(unlocked yes)
			(layer "B.Fab")
			(hide yes)
			(effects
				(font
					(size 1.016 1.016)
					(thickness 0.1524)
				)
				(justify mirror)
			)
		)
		(property "Device Type" "R402H16"
			(at -0.064008 -5.517896 90)
			(unlocked yes)
			(layer "B.Fab")
			(hide yes)
			(effects
				(font
					(size 1.016 1.016)
					(thickness 0.1524)
				)
				(justify mirror)
			)
		)
		(duplicate_pad_numbers_are_jumpers no)
		(fp_line
			(start 0.508 -0.9398)
			(end 0.508 0.9398)
			(stroke
				(width 0.1524)
				(type default)
			)
			(layer "B.SilkS")
		)
		(fp_line
			(start -0.508 -0.9398)
			(end 0.508 -0.9398)
			(stroke
				(width 0.1524)
				(type default)
			)
			(layer "B.SilkS")
		)
		(fp_rect
			(start 0.508 0.9398)
			(end -0.508 -0.9398)
			(stroke
				(width 0)
				(type default)
			)
			(fill no)
			(layer "B.CrtYd")
		)
		(fp_rect
			(start 0.508 0.9398)
			(end -0.508 -0.9398)
			(stroke
				(width 0)
				(type default)
			)
			(fill no)
			(layer "B.Fab")
		)
		(pad "1" smd custom
			(at 0 -0.4445 270)
			(size 0.1397 0.1397)
			(layers "B.Cu" "B.Mask" "B.Paste")
			(net "TEMP_3_A0")
			(options
				(clearance outline)
				(anchor circle)
			)
			(primitives
				(gr_poly
					(pts
						(arc
							(start -0.1778 0.2794)
							(mid -0.249642 0.249642)
							(end -0.2794 0.1778)
						)
						(arc
							(start -0.2794 -0.1778)
							(mid -0.249642 -0.249642)
							(end -0.1778 -0.2794)
						)
						(arc
							(start 0.1778 -0.2794)
							(mid 0.249642 -0.249642)
							(end 0.2794 -0.1778)
						)
						(arc
							(start 0.2794 0.1778)
							(mid 0.249642 0.249642)
							(end 0.1778 0.2794)
						)
					)
					(width 0)
					(fill yes)
				)
			)
		)
		(pad "2" smd custom
			(at 0 0.4445 270)
			(size 0.1397 0.1397)
			(layers "B.Cu" "B.Mask" "B.Paste")
			(net "GND")
			(options
				(clearance outline)
				(anchor circle)
			)
			(primitives
				(gr_poly
					(pts
						(arc
							(start -0.1778 0.2794)
							(mid -0.249642 0.249642)
							(end -0.2794 0.1778)
						)
						(arc
							(start -0.2794 -0.1778)
							(mid -0.249642 -0.249642)
							(end -0.1778 -0.2794)
						)
						(arc
							(start 0.1778 -0.2794)
							(mid 0.249642 -0.249642)
							(end 0.2794 -0.1778)
						)
						(arc
							(start 0.2794 0.1778)
							(mid 0.249642 0.249642)
							(end 0.1778 0.2794)
						)
					)
					(width 0)
					(fill yes)
				)
			)
		)
	)
	(footprint ""
		(layer "B.Cu")
		(at 55.8038 -143.0274)
		(property "Reference" "TP54"
			(at 0 0 0)
			(layer "B.SilkS")
			(hide yes)
			(effects
				(font
					(size 1.27 1.27)
				)
				(justify mirror)
			)
		)
		(property "Value" "TPAD28-2-GP"
			(at 0.0127 -1.6637 0)
			(unlocked yes)
			(layer "B.Fab")
			(hide yes)
			(effects
				(font
					(size 1.016 1.016)
					(thickness 0.1524)
				)
				(justify mirror)
			)
		)
		(property "Device Type" "TPAD28"
			(at 0.0127 -3.1877 0)
			(unlocked yes)
			(layer "B.Fab")
			(hide yes)
			(effects
				(font
					(size 1.016 1.016)
					(thickness 0.1524)
				)
				(justify mirror)
			)
		)
		(duplicate_pad_numbers_are_jumpers no)
		(fp_poly
			(pts
				(arc
					(start 0.3556 0)
					(mid -0.3556 0)
					(end 0.3556 0)
				)
			)
			(stroke
				(width 0)
				(type default)
			)
			(fill no)
			(layer "B.CrtYd")
		)
		(fp_poly
			(pts
				(arc
					(start 0.6096 0)
					(mid -0.6096 0)
					(end 0.6096 0)
				)
			)
			(stroke
				(width 0)
				(type default)
			)
			(fill no)
			(layer "B.Fab")
		)
		(pad "1" smd circle
			(at 0 0 180)
			(size 0.7112 0.7112)
			(layers "B.Cu" "B.Mask" "B.Paste")
			(net "TP_BMC_GPIOA6")
		)
	)
	(footprint ""
		(layer "B.Cu")
		(at 51.40452 -144.26438)
		(property "Reference" "TP78"
			(at 0 0 0)
			(layer "B.SilkS")
			(hide yes)
			(effects
				(font
					(size 1.27 1.27)
				)
				(justify mirror)
			)
		)
		(property "Value" "TPAD28-2-GP"
			(at 0.0127 -1.6637 0)
			(unlocked yes)
			(layer "B.Fab")
			(hide yes)
			(effects
				(font
					(size 1.016 1.016)
					(thickness 0.1524)
				)
				(justify mirror)
			)
		)
		(property "Device Type" "TPAD28"
			(at 0.0127 -3.1877 0)
			(unlocked yes)
			(layer "B.Fab")
			(hide yes)
			(effects
				(font
					(size 1.016 1.016)
					(thickness 0.1524)
				)
				(justify mirror)
			)
		)
		(duplicate_pad_numbers_are_jumpers no)
		(fp_poly
			(pts
				(arc
					(start 0.3556 0)
					(mid -0.3556 0)
					(end 0.3556 0)
				)
			)
			(stroke
				(width 0)
				(type default)
			)
			(fill no)
			(layer "B.CrtYd")
		)
		(fp_poly
			(pts
				(arc
					(start 0.6096 0)
					(mid -0.6096 0)
					(end 0.6096 0)
				)
			)
			(stroke
				(width 0)
				(type default)
			)
			(fill no)
			(layer "B.Fab")
		)
		(pad "1" smd circle
			(at 0 0 180)
			(size 0.7112 0.7112)
			(layers "B.Cu" "B.Mask" "B.Paste")
			(net "JTAG_BMC_TRST_N")
		)
	)
	(footprint ""
		(layer "B.Cu")
		(at 210.0072 -107.343448 -90)
		(property "Reference" "R814"
			(at 0 0 90)
			(layer "B.SilkS")
			(hide yes)
			(effects
				(font
					(size 1.27 1.27)
				)
				(justify mirror)
			)
		)
		(property "Value" "1KR2F-3-GP"
			(at -0.064008 -3.993896 270)
			(unlocked yes)
			(layer "B.Fab")
			(hide yes)
			(effects
				(font
					(size 1.016 1.016)
					(thickness 0.1524)
				)
				(justify mirror)
			)
		)
		(property "Device Type" "R402H16"
			(at -0.064008 -5.517896 270)
			(unlocked yes)
			(layer "B.Fab")
			(hide yes)
			(effects
				(font
					(size 1.016 1.016)
					(thickness 0.1524)
				)
				(justify mirror)
			)
		)
		(duplicate_pad_numbers_are_jumpers no)
		(fp_line
			(start -0.508 -0.9398)
			(end 0.508 -0.9398)
			(stroke
				(width 0.1524)
				(type default)
			)
			(layer "B.SilkS")
		)
		(fp_line
			(start 0.508 -0.9398)
			(end 0.508 0.9398)
			(stroke
				(width 0.1524)
				(type default)
			)
			(layer "B.SilkS")
		)
		(fp_rect
			(start 0.508 0.9398)
			(end -0.508 -0.9398)
			(stroke
				(width 0)
				(type default)
			)
			(fill no)
			(layer "B.CrtYd")
		)
		(fp_rect
			(start 0.508 0.9398)
			(end -0.508 -0.9398)
			(stroke
				(width 0)
				(type default)
			)
			(fill no)
			(layer "B.Fab")
		)
		(pad "1" smd custom
			(at 0 -0.4445 90)
			(size 0.1397 0.1397)
			(layers "B.Cu" "B.Mask" "B.Paste")
			(net "P1V8_STBY")
			(options
				(clearance outline)
				(anchor circle)
			)
			(primitives
				(gr_poly
					(pts
						(arc
							(start -0.1778 0.2794)
							(mid -0.249642 0.249642)
							(end -0.2794 0.1778)
						)
						(arc
							(start -0.2794 -0.1778)
							(mid -0.249642 -0.249642)
							(end -0.1778 -0.2794)
						)
						(arc
							(start 0.1778 -0.2794)
							(mid 0.249642 -0.249642)
							(end 0.2794 -0.1778)
						)
						(arc
							(start 0.2794 0.1778)
							(mid 0.249642 0.249642)
							(end 0.1778 0.2794)
						)
					)
					(width 0)
					(fill yes)
				)
			)
		)
		(pad "2" smd custom
			(at 0 0.4445 90)
			(size 0.1397 0.1397)
			(layers "B.Cu" "B.Mask" "B.Paste")
			(net "I2C_M2_1_1V8_SDA")
			(options
				(clearance outline)
				(anchor circle)
			)
			(primitives
				(gr_poly
					(pts
						(arc
							(start -0.1778 0.2794)
							(mid -0.249642 0.249642)
							(end -0.2794 0.1778)
						)
						(arc
							(start -0.2794 -0.1778)
							(mid -0.249642 -0.249642)
							(end -0.1778 -0.2794)
						)
						(arc
							(start 0.1778 -0.2794)
							(mid 0.249642 -0.249642)
							(end 0.2794 -0.1778)
						)
						(arc
							(start 0.2794 0.1778)
							(mid 0.249642 0.249642)
							(end 0.1778 0.2794)
						)
					)
					(width 0)
					(fill yes)
				)
			)
		)
	)
)
